(kicad_pcb
	(version 20221018)
	(generator pcbnew)
	(general
    (thickness 1.518)
  )
	(paper "A4")
	(title_block
    (title "Kria K26 Devboard")
    (date "2024-03-26")
    (rev "1.2.5")
    (comment 1 "www.antmicro.com")
    (comment 2 "Antmicro Ltd.")
		(comment 9 "footprints 251-258 of 660")
	)
	(layers
    (0 "F.Cu" mixed)
    (1 "In1.Cu" power)
    (2 "In2.Cu" mixed)
    (3 "In3.Cu" power)
    (4 "In4.Cu" mixed)
    (5 "In5.Cu" power)
    (6 "In6.Cu" mixed)
    (31 "B.Cu" power)
    (32 "B.Adhes" user "B.Adhesive")
    (33 "F.Adhes" user "F.Adhesive")
    (34 "B.Paste" user)
    (35 "F.Paste" user)
    (36 "B.SilkS" user "B.Silkscreen")
    (37 "F.SilkS" user "F.Silkscreen")
    (38 "B.Mask" user)
    (39 "F.Mask" user)
    (40 "Dwgs.User" user "User.Drawings")
    (41 "Cmts.User" user "User.Comments")
    (42 "Eco1.User" user "User.Eco1")
    (43 "Eco2.User" user "User.Eco2")
    (44 "Edge.Cuts" user)
    (45 "Margin" user)
    (46 "B.CrtYd" user "B.Courtyard")
    (47 "F.CrtYd" user "F.Courtyard")
    (48 "B.Fab" user)
    (49 "F.Fab" user)
  )
	(footprint "kria-k26-devboard-footprints:LED_0603_1608Metric_G" (layer "F.Cu")
    (at 180.925 115.425)
    (descr "LED SMD 0603 Green")
    (tags "LED SMD 0603 Green")
    (property "Author" "Antmicro")
    (property "Color" "Green")
    (property "License" "Apache-2.0")
    (property "MPN" "LG L29K-G2J1-24-Z")
    (property "Manufacturer" "OSRAM")
    (property "Sheetfile" "dc-dc-conventers.kicad_sch")
    (property "Sheetname" "DC/DC conventers")
    (property "ki_description" "LED, Green, SMT, 0603, 20 mA, 2.1 V, 570 nm")
    (property "ki_keywords" "0603, SMT, DIODE, SEMICONDUCTOR, UNICOLOR")
    (attr smd)
    (fp_text reference "D16" (at 1.215 0.745) (layer "F.SilkS")
        (effects (font (size 0.7 0.7) (thickness 0.15)) (justify left bottom))
    )
    (fp_text value "LED_G_0603_LG_L29K-G2J1-24-Z" (at 0 1.6) (layer "F.Fab") hide
        (effects (font (size 0.7 0.7) (thickness 0.15)) (justify left bottom))
    )
    (fp_text user "${REFERENCE}" (at -1.31 3.769) (layer "F.Fab") hide
        (effects (font (size 0.7 0.7) (thickness 0.15)) (justify left bottom))
    )
    (fp_text user "License: Apache-2.0" (at -1.31 5.769) (layer "F.Fab") hide
        (effects (font (size 0.7 0.7) (thickness 0.15)) (justify left bottom))
    )
    (fp_text user "Author: Antmicro" (at -1.31 4.769) (layer "F.Fab") hide
        (effects (font (size 0.7 0.7) (thickness 0.15)) (justify left bottom))
    )
    (fp_line (start -0.27 -0.35) (end 0.27 -0.35)
      (stroke (width 0.15) (type solid)) (layer "F.SilkS"))
    (fp_line (start -0.27 0.351) (end 0.27 0.351)
      (stroke (width 0.15) (type solid)) (layer "F.SilkS"))
    (fp_line (start -0.106328 -0.200008) (end -0.106328 0.199992)
      (stroke (width 0.1) (type solid)) (layer "F.SilkS"))
    (fp_line (start -0.106328 -0.200008) (end 0.093672 -0.000008)
      (stroke (width 0.1) (type solid)) (layer "F.SilkS"))
    (fp_line (start -0.106328 -0.000008) (end -0.29 0)
      (stroke (width 0.1) (type solid)) (layer "F.SilkS"))
    (fp_line (start 0.093672 -0.200008) (end 0.093672 0.199992)
      (stroke (width 0.1) (type solid)) (layer "F.SilkS"))
    (fp_line (start 0.093672 -0.000008) (end -0.106328 0.199992)
      (stroke (width 0.1) (type solid)) (layer "F.SilkS"))
    (fp_line (start 0.093672 -0.000008) (end 0.293672 -0.000008)
      (stroke (width 0.1) (type solid)) (layer "F.SilkS"))
    (fp_line (start 1.25 0.32) (end 1.25 -0.32)
      (stroke (width 0.15) (type solid)) (layer "F.SilkS"))
    (fp_rect (start 1.26 0.65) (end -1.26 -0.65)
      (stroke (width 0.05) (type solid)) (fill none) (layer "F.CrtYd"))
    (fp_line (start -0.599 0) (end -0.201 0)
      (stroke (width 0.15) (type solid)) (layer "F.Fab"))
    (fp_line (start -0.201 -0.2) (end -0.201 0)
      (stroke (width 0.15) (type solid)) (layer "F.Fab"))
    (fp_line (start -0.201 0) (end -0.201 0.202)
      (stroke (width 0.15) (type solid)) (layer "F.Fab"))
    (fp_line (start -0.201 0.202) (end 0.101 0)
      (stroke (width 0.15) (type solid)) (layer "F.Fab"))
    (fp_line (start 0.101 0) (end -0.201 -0.2)
      (stroke (width 0.15) (type solid)) (layer "F.Fab"))
    (fp_line (start 0.199 -0.2) (end 0.199 -0.1)
      (stroke (width 0.15) (type solid)) (layer "F.Fab"))
    (fp_line (start 0.199 0) (end 0.597 0)
      (stroke (width 0.15) (type solid)) (layer "F.Fab"))
    (fp_line (start 0.199 0.202) (end 0.199 -0.1)
      (stroke (width 0.15) (type solid)) (layer "F.Fab"))
    (fp_rect (start -0.848 -0.4) (end 0.85 0.402)
      (stroke (width 0.15) (type solid)) (fill none) (layer "F.Fab"))
    (pad "1" smd rect (at -0.75 0 180) (size 0.8 0.8) (layers "F.Cu" "F.Paste" "F.Mask")
      (net 241 "Net-(D16-Pad1)") (pintype "passive"))
    (pad "2" smd rect (at 0.75 0 180) (size 0.8 0.8) (layers "F.Cu" "F.Paste" "F.Mask")
      (net 337 "Net-(Q18-C)") (pinfunction "2") (pintype "passive"))
  )
	(footprint "kria-k26-devboard-footprints:C_0603_1608Metric" (layer "F.Cu")
    (at 175.75 117.6 -90)
    (descr "Capacitor SMD 0603")
    (tags "capacitor 0603")
    (property "Author" "Antmicro")
    (property "Dielectric" "")
    (property "License" "Apache-2.0")
    (property "MPN" "GRM188R60J226MEA0D")
    (property "Manufacturer" "Murata")
    (property "Sheetfile" "dc-dc-conventers.kicad_sch")
    (property "Sheetname" "DC/DC conventers")
    (property "Val" "22u")
    (property "Voltage" "")
    (property "ki_description" " ")
    (attr smd)
    (fp_text reference "C217" (at -4.11 0.87 90) (layer "F.SilkS")
        (effects (font (size 0.7 0.7) (thickness 0.15)) (justify left bottom))
    )
    (fp_text value "C_22u_0603" (at 0 1.6 -90) (layer "F.Fab") hide
        (effects (font (size 0.7 0.7) (thickness 0.15)) (justify left bottom))
    )
    (fp_text user "Author: Antmicro" (at -1.682 4.894 -90) (layer "F.Fab") hide
        (effects (font (size 0.7 0.7) (thickness 0.15)) (justify left bottom))
    )
    (fp_text user "${REFERENCE}" (at -1.682 3.895 -90) (layer "F.Fab") hide
        (effects (font (size 0.7 0.7) (thickness 0.15)) (justify left bottom))
    )
    (fp_text user "License: Apache-2.0" (at -1.682 5.895 -90) (layer "F.Fab") hide
        (effects (font (size 0.7 0.7) (thickness 0.15)) (justify left bottom))
    )
    (fp_line (start -0.3 -0.3) (end 0.3 -0.3)
      (stroke (width 0.15) (type solid)) (layer "F.SilkS"))
    (fp_line (start -0.3 0.3) (end 0.3 0.3)
      (stroke (width 0.15) (type solid)) (layer "F.SilkS"))
    (fp_rect (start -1.24 -0.7) (end 1.24 0.7)
      (stroke (width 0.05) (type solid)) (fill none) (layer "F.CrtYd"))
    (fp_rect (start -0.8 -0.4) (end 0.8 0.4)
      (stroke (width 0.15) (type solid)) (fill none) (layer "F.Fab"))
    (pad "1" smd roundrect (at -0.7 0 270) (size 0.6 0.8) (layers "F.Cu" "F.Paste" "F.Mask") (roundrect_rratio 0.2)
      (net 767 "/Power Supply/DC/DC conventers/PS_1V8_OUT") (pintype "passive"))
    (pad "2" smd roundrect (at 0.7 0 270) (size 0.6 0.8) (layers "F.Cu" "F.Paste" "F.Mask") (roundrect_rratio 0.2)
      (net 1 "GND") (pintype "passive"))
  )
	(footprint "kria-k26-devboard-footprints:C_0603_1608Metric" (layer "F.Cu")
    (at 176.95 117.6 -90)
    (descr "Capacitor SMD 0603")
    (tags "capacitor 0603")
    (property "Author" "Antmicro")
    (property "Dielectric" "")
    (property "License" "Apache-2.0")
    (property "MPN" "GRM188R60J226MEA0D")
    (property "Manufacturer" "Murata")
    (property "Sheetfile" "dc-dc-conventers.kicad_sch")
    (property "Sheetname" "DC/DC conventers")
    (property "Val" "22u")
    (property "Voltage" "")
    (property "ki_description" " ")
    (attr smd)
    (fp_text reference "C213" (at -4.1 1.18 90) (layer "F.SilkS")
        (effects (font (size 0.7 0.7) (thickness 0.15)) (justify left bottom))
    )
    (fp_text value "C_22u_0603" (at 0 1.6 -90) (layer "F.Fab") hide
        (effects (font (size 0.7 0.7) (thickness 0.15)) (justify left bottom))
    )
    (fp_text user "Author: Antmicro" (at -1.682 4.894 -90) (layer "F.Fab") hide
        (effects (font (size 0.7 0.7) (thickness 0.15)) (justify left bottom))
    )
    (fp_text user "License: Apache-2.0" (at -1.682 5.895 -90) (layer "F.Fab") hide
        (effects (font (size 0.7 0.7) (thickness 0.15)) (justify left bottom))
    )
    (fp_text user "${REFERENCE}" (at -1.682 3.895 -90) (layer "F.Fab") hide
        (effects (font (size 0.7 0.7) (thickness 0.15)) (justify left bottom))
    )
    (fp_line (start -0.3 -0.3) (end 0.3 -0.3)
      (stroke (width 0.15) (type solid)) (layer "F.SilkS"))
    (fp_line (start -0.3 0.3) (end 0.3 0.3)
      (stroke (width 0.15) (type solid)) (layer "F.SilkS"))
    (fp_rect (start -1.24 -0.7) (end 1.24 0.7)
      (stroke (width 0.05) (type solid)) (fill none) (layer "F.CrtYd"))
    (fp_rect (start -0.8 -0.4) (end 0.8 0.4)
      (stroke (width 0.15) (type solid)) (fill none) (layer "F.Fab"))
    (pad "1" smd roundrect (at -0.7 0 270) (size 0.6 0.8) (layers "F.Cu" "F.Paste" "F.Mask") (roundrect_rratio 0.2)
      (net 767 "/Power Supply/DC/DC conventers/PS_1V8_OUT") (pintype "passive"))
    (pad "2" smd roundrect (at 0.7 0 270) (size 0.6 0.8) (layers "F.Cu" "F.Paste" "F.Mask") (roundrect_rratio 0.2)
      (net 1 "GND") (pintype "passive"))
  )
	(footprint "kria-k26-devboard-footprints:C_0402_1005Metric" (layer "F.Cu")
    (at 181.65 117.475 90)
    (descr "Capacitor SMD 0402")
    (tags "capacitor SMD 0402")
    (property "Author" "Antmicro")
    (property "Dielectric" "X5R")
    (property "License" "Apache-2.0")
    (property "MPN" "GRM155R61H104KE14D")
    (property "Manufacturer" "Murata")
    (property "Sheetfile" "dc-dc-conventers.kicad_sch")
    (property "Sheetname" "DC/DC conventers")
    (property "Val" "100n")
    (property "Voltage" "50V")
    (property "ki_description" " ")
    (attr smd)
    (fp_text reference "C208" (at -4.655 2.37 90) (layer "F.SilkS")
        (effects (font (size 0.7 0.7) (thickness 0.15)) (justify left bottom))
    )
    (fp_text value "C_100n_0402" (at 0 1.4 90) (layer "F.Fab") hide
        (effects (font (size 0.7 0.7) (thickness 0.15)) (justify left bottom))
    )
    (fp_text user "Author: Antmicro" (at -0.932 4.17 90) (layer "F.Fab") hide
        (effects (font (size 0.7 0.7) (thickness 0.15)) (justify left bottom))
    )
    (fp_text user "${REFERENCE}" (at -0.932 3.168 90) (layer "F.Fab") hide
        (effects (font (size 0.7 0.7) (thickness 0.15)) (justify left bottom))
    )
    (fp_text user "License: Apache-2.0" (at -0.932 5.17 90) (layer "F.Fab") hide
        (effects (font (size 0.7 0.7) (thickness 0.15)) (justify left bottom))
    )
    (fp_rect (start -0.94 -0.47) (end 0.94 0.47)
      (stroke (width 0.05) (type solid)) (fill none) (layer "F.CrtYd"))
    (fp_rect (start -0.499 -0.249) (end 0.499 0.249)
      (stroke (width 0.15) (type solid)) (fill none) (layer "F.Fab"))
    (pad "1" smd roundrect (at -0.484 0 90) (size 0.59 0.64) (layers "F.Cu" "F.Paste" "F.Mask") (roundrect_rratio 0.25)
      (net 276 "Net-(U51-BST)") (pintype "passive"))
    (pad "2" smd roundrect (at 0.484 0 90) (size 0.59 0.64) (layers "F.Cu" "F.Paste" "F.Mask") (roundrect_rratio 0.25)
      (net 311 "/Power Supply/DC/DC conventers/SW_PS_1V8") (pintype "passive"))
  )
	(footprint "kria-k26-devboard-footprints:C_0603_1608Metric" (layer "F.Cu")
    (at 177 120.275 90)
    (descr "Capacitor SMD 0603")
    (tags "capacitor 0603")
    (property "Author" "Antmicro")
    (property "Dielectric" "")
    (property "License" "Apache-2.0")
    (property "MPN" "C1608X5R1E106M080AC")
    (property "Manufacturer" "TDK")
    (property "Sheetfile" "dc-dc-conventers.kicad_sch")
    (property "Sheetname" "DC/DC conventers")
    (property "Val" "10u/25V")
    (property "Voltage" "")
    (property "ki_description" " ")
    (attr smd)
    (fp_text reference "C203" (at -3.975 1.82 90) (layer "F.SilkS")
        (effects (font (size 0.7 0.7) (thickness 0.15)) (justify left bottom))
    )
    (fp_text value "C_10u_25V_0603" (at 0 1.6 90) (layer "F.Fab") hide
        (effects (font (size 0.7 0.7) (thickness 0.15)) (justify left bottom))
    )
    (fp_text user "License: Apache-2.0" (at -1.682 5.895 90) (layer "F.Fab") hide
        (effects (font (size 0.7 0.7) (thickness 0.15)) (justify left bottom))
    )
    (fp_text user "${REFERENCE}" (at -1.682 3.895 90) (layer "F.Fab") hide
        (effects (font (size 0.7 0.7) (thickness 0.15)) (justify left bottom))
    )
    (fp_text user "Author: Antmicro" (at -1.682 4.894 90) (layer "F.Fab") hide
        (effects (font (size 0.7 0.7) (thickness 0.15)) (justify left bottom))
    )
    (fp_line (start -0.3 -0.3) (end 0.3 -0.3)
      (stroke (width 0.15) (type solid)) (layer "F.SilkS"))
    (fp_line (start -0.3 0.3) (end 0.3 0.3)
      (stroke (width 0.15) (type solid)) (layer "F.SilkS"))
    (fp_rect (start -1.24 -0.7) (end 1.24 0.7)
      (stroke (width 0.05) (type solid)) (fill none) (layer "F.CrtYd"))
    (fp_rect (start -0.8 -0.4) (end 0.8 0.4)
      (stroke (width 0.15) (type solid)) (fill none) (layer "F.Fab"))
    (pad "1" smd roundrect (at -0.7 0 90) (size 0.6 0.8) (layers "F.Cu" "F.Paste" "F.Mask") (roundrect_rratio 0.2)
      (net 14 "/Power Supply/DC/DC conventers/DC_MAIN_BUS") (pintype "passive"))
    (pad "2" smd roundrect (at 0.7 0 90) (size 0.6 0.8) (layers "F.Cu" "F.Paste" "F.Mask") (roundrect_rratio 0.2)
      (net 1 "GND") (pintype "passive"))
  )
	(footprint "kria-k26-devboard-footprints:L_0806_2016Metric" (layer "F.Cu")
    (at 179.41 117.41 180)
    (property "Author" "Antmicro")
    (property "IMax" "")
    (property "ISat" "")
    (property "License" "Apache-2.0")
    (property "MPN" "SRP2010-1R0M")
    (property "Manufacturer" "Bourns")
    (property "Sheetfile" "dc-dc-conventers.kicad_sch")
    (property "Sheetname" "DC/DC conventers")
    (property "Size" "2.0x1.6")
    (property "Val" "1u/2.6A")
    (attr smd)
    (fp_text reference "L5" (at -2.75 -3.52 270) (layer "F.SilkS")
        (effects (font (size 0.7 0.7) (thickness 0.15)) (justify left bottom))
    )
    (fp_text value "L_1u_2.6A_0806" (at 0 2 180) (layer "F.Fab") hide
        (effects (font (size 0.7 0.7) (thickness 0.15)) (justify left bottom))
    )
    (fp_text user "${REFERENCE}" (at -1.9 3.1 180) (layer "F.Fab") hide
        (effects (font (size 0.7 0.7) (thickness 0.15)) (justify left bottom))
    )
    (fp_text user "License: Apache-2.0" (at -1.9 5.75 180) (layer "F.Fab") hide
        (effects (font (size 0.7 0.7) (thickness 0.15)) (justify left bottom))
    )
    (fp_text user "Author: Antmicro" (at -1.9 4.4 180) (layer "F.Fab") hide
        (effects (font (size 0.7 0.7) (thickness 0.15)) (justify left bottom))
    )
    (fp_line (start -0.301 0.9) (end 0.299 0.9)
      (stroke (width 0.15) (type solid)) (layer "F.SilkS"))
    (fp_line (start -0.3 -0.9) (end 0.298 -0.9)
      (stroke (width 0.15) (type solid)) (layer "F.SilkS"))
    (fp_rect (start -1.75 -1.05) (end 1.75 1.05)
      (stroke (width 0.05) (type solid)) (fill none) (layer "F.CrtYd"))
    (fp_rect (start -0.951 -0.882) (end 0.949 0.875)
      (stroke (width 0.15) (type solid)) (fill none) (layer "F.Fab"))
    (pad "1" smd roundrect (at -1.1 -0.001 180) (size 1 1.8) (layers "F.Cu" "F.Paste" "F.Mask") (roundrect_rratio 0.15)
      (net 311 "/Power Supply/DC/DC conventers/SW_PS_1V8") (pintype "passive"))
    (pad "2" smd roundrect (at 1.1 -0.001 180) (size 1 1.8) (layers "F.Cu" "F.Paste" "F.Mask") (roundrect_rratio 0.15)
      (net 767 "/Power Supply/DC/DC conventers/PS_1V8_OUT") (pintype "passive"))
  )
	(footprint "kria-k26-devboard-footprints:C_0402_1005Metric" (layer "F.Cu")
    (at 171.87 117.3 90)
    (descr "Capacitor SMD 0402")
    (tags "capacitor SMD 0402")
    (property "Author" "Antmicro")
    (property "Dielectric" "X5R")
    (property "License" "Apache-2.0")
    (property "MPN" "GRM155R61H104KE14D")
    (property "Manufacturer" "Murata")
    (property "Sheetfile" "dc-dc-conventers.kicad_sch")
    (property "Sheetname" "DC/DC conventers")
    (property "Val" "100n")
    (property "Voltage" "50V")
    (property "ki_description" " ")
    (attr smd)
    (fp_text reference "C209" (at -1.05 0.37 180) (layer "F.SilkS")
        (effects (font (size 0.7 0.7) (thickness 0.15)) (justify left bottom))
    )
    (fp_text value "C_100n_0402" (at 0 1.4 90) (layer "F.Fab") hide
        (effects (font (size 0.7 0.7) (thickness 0.15)) (justify left bottom))
    )
    (fp_text user "${REFERENCE}" (at -0.932 3.168 90) (layer "F.Fab") hide
        (effects (font (size 0.7 0.7) (thickness 0.15)) (justify left bottom))
    )
    (fp_text user "Author: Antmicro" (at -0.932 4.17 90) (layer "F.Fab") hide
        (effects (font (size 0.7 0.7) (thickness 0.15)) (justify left bottom))
    )
    (fp_text user "License: Apache-2.0" (at -0.932 5.17 90) (layer "F.Fab") hide
        (effects (font (size 0.7 0.7) (thickness 0.15)) (justify left bottom))
    )
    (fp_rect (start -0.94 -0.47) (end 0.94 0.47)
      (stroke (width 0.05) (type solid)) (fill none) (layer "F.CrtYd"))
    (fp_rect (start -0.499 -0.249) (end 0.499 0.249)
      (stroke (width 0.15) (type solid)) (fill none) (layer "F.Fab"))
    (pad "1" smd roundrect (at -0.484 0 90) (size 0.59 0.64) (layers "F.Cu" "F.Paste" "F.Mask") (roundrect_rratio 0.25)
      (net 314 "Net-(U52-BST)") (pintype "passive"))
    (pad "2" smd roundrect (at 0.484 0 90) (size 0.59 0.64) (layers "F.Cu" "F.Paste" "F.Mask") (roundrect_rratio 0.25)
      (net 312 "/Power Supply/DC/DC conventers/SW_PS_1V2") (pintype "passive"))
  )
	(footprint "kria-k26-devboard-footprints:R_0402_1005Metric" (layer "F.Cu")
    (at 168.5 131.25)
    (descr "Resistor SMD 0402")
    (tags "resistor SMD 0402")
    (property "Author" "Antmicro")
    (property "License" "Apache-2.0")
    (property "MPN" "CR0402-FX-1001GLF")
    (property "Manufacturer" "Bourns")
    (property "Sheetfile" "dc-dc-conventers.kicad_sch")
    (property "Sheetname" "DC/DC conventers")
    (property "Tolerance" "1%")
    (property "Val" "1k")
    (property "ki_description" "1k resistor in 0402 package with 1% tolerance")
    (attr smd)
    (fp_text reference "R126" (at -3.68 0.38) (layer "F.SilkS")
        (effects (font (size 0.7 0.7) (thickness 0.15)) (justify left bottom))
    )
    (fp_text value "R_1k_0402" (at 0 1.4) (layer "F.Fab") hide
        (effects (font (size 0.7 0.7) (thickness 0.15)) (justify left bottom))
    )
    (fp_text user "Author: Antmicro" (at -0.95 4.169) (layer "F.Fab") hide
        (effects (font (size 0.7 0.7) (thickness 0.15)) (justify left bottom))
    )
    (fp_text user "License: Apache-2.0" (at -0.95 5.169) (layer "F.Fab") hide
        (effects (font (size 0.7 0.7) (thickness 0.15)) (justify left bottom))
    )
    (fp_text user "${REFERENCE}" (at -0.95 3.168) (layer "F.Fab") hide
        (effects (font (size 0.7 0.7) (thickness 0.15)) (justify left bottom))
    )
    (fp_rect (start -0.93 -0.47) (end 0.93 0.47)
      (stroke (width 0.05) (type solid)) (fill none) (layer "F.CrtYd"))
    (fp_rect (start -0.5 -0.25) (end 0.5 0.25)
      (stroke (width 0.15) (type solid)) (fill none) (layer "F.Fab"))
    (pad "1" smd roundrect (at -0.485 0) (size 0.59 0.64) (layers "F.Cu" "F.Paste" "F.Mask") (roundrect_rratio 0.25)
      (net 765 "/Power Supply/DC/DC conventers/PS_3V3_OUT") (pintype "passive"))
    (pad "2" smd roundrect (at 0.485 0) (size 0.59 0.64) (layers "F.Cu" "F.Paste" "F.Mask") (roundrect_rratio 0.25)
      (net 239 "Net-(D14-Pad1)") (pintype "passive"))
  )
)
